(kicad_pcb
	(version 20260206)
	(generator "pcbnew")
	(generator_version "10.0")
	(general
		(thickness 1.6)
		(legacy_teardrops no)
	)
	(paper "A4")
	(title_block
		(title "Wiwynn_Tioga_Pass_MB.brd")
		(comment 1 "Tioga Pass / footprints 4328-4335 of 4770")
	)
	(layers
		(0 "F.Cu" signal "TOP")
		(4 "In1.Cu" signal "L2GND")
		(6 "In2.Cu" signal "L3")
		(8 "In3.Cu" signal "L4GND")
		(10 "In4.Cu" signal "L5")
		(12 "In5.Cu" signal "L6GND")
		(14 "In6.Cu" signal "L7VCC")
		(16 "In7.Cu" signal "L8VCC")
		(18 "In8.Cu" signal "L9GND")
		(20 "In9.Cu" signal "L10")
		(22 "In10.Cu" signal "L11GND")
		(24 "In11.Cu" signal "L12")
		(26 "In12.Cu" signal "L13GND")
		(2 "B.Cu" signal "BOTTOM")
		(9 "F.Adhes" user "F.Adhesive")
		(11 "B.Adhes" user "B.Adhesive")
		(13 "F.Paste" user "Package Geometry/Pastemask Top")
		(15 "B.Paste" user "Package Geometry/Pastemask Bottom")
		(5 "F.SilkS" user "Ref Des/Silkscreen Top")
		(7 "B.SilkS" user "Ref Des/Silkscreen Bottom")
		(1 "F.Mask" user "Board Geometry/Soldermask Top")
		(3 "B.Mask" user "Board Geometry/Soldermask Bottom")
		(17 "Dwgs.User" user "User.Drawings")
		(19 "Cmts.User" user "User.Comments")
		(21 "Eco1.User" user "User.Eco1")
		(23 "Eco2.User" user "User.Eco2")
		(25 "Edge.Cuts" user "Board Geometry/Outline")
		(27 "Margin" user)
		(31 "F.CrtYd" user "Package Geometry/Place Bound Top")
		(29 "B.CrtYd" user "Package Geometry/Place Bound Bottom")
		(35 "F.Fab" user "Ref Des/Assembly Top")
		(33 "B.Fab" user "Ref Des/Assembly Bottom")
	)
	(footprint ""
		(layer "B.Cu")
		(at 432.0032 -23.4188)
		(property "Reference" "R1U17"
			(at 0 0 0)
			(layer "B.SilkS")
			(hide yes)
			(effects
				(font
					(size 1.27 1.27)
				)
				(justify mirror)
			)
		)
		(property "Value" ""
			(at 0 0 0)
			(layer "B.Fab")
			(effects
				(font
					(size 1.27 1.27)
				)
				(justify mirror)
			)
		)
		(duplicate_pad_numbers_are_jumpers no)
		(fp_poly
			(pts
				(xy 0.2794 -0.1016) (xy -0.2794 -0.1016) (xy -0.2794 0.9906) (xy 0.2794 0.9906)
			)
			(stroke
				(width 0)
				(type default)
			)
			(fill no)
			(layer "B.CrtYd")
		)
		(fp_line
			(start -0.2794 -0.1016)
			(end 0.2794 -0.1016)
			(stroke
				(width 0.1)
				(type default)
			)
			(layer "B.Fab")
		)
		(fp_line
			(start -0.2794 0.9906)
			(end -0.2794 -0.1016)
			(stroke
				(width 0.1)
				(type default)
			)
			(layer "B.Fab")
		)
		(fp_line
			(start 0.2794 -0.1016)
			(end 0.2794 0.9906)
			(stroke
				(width 0.1)
				(type default)
			)
			(layer "B.Fab")
		)
		(fp_line
			(start 0.2794 0.9906)
			(end -0.2794 0.9906)
			(stroke
				(width 0.1)
				(type default)
			)
			(layer "B.Fab")
		)
		(pad "1" smd rect
			(at 0 0 180)
			(size 0.508 0.508)
			(layers "B.Cu" "B.Mask" "B.Paste")
			(net "FM_BOARD_SKU_ID2")
		)
		(pad "2" smd rect
			(at 0 0.889 180)
			(size 0.508 0.508)
			(layers "B.Cu" "B.Mask" "B.Paste")
			(net "GND")
		)
		(zone
			(layer "B.Cu")
			(hatch none 0.5)
			(connect_pads
				(clearance 0)
			)
			(min_thickness 0.25)
			(keepout
				(tracks allowed)
				(vias not_allowed)
				(pads allowed)
				(copperpour not_allowed)
				(footprints allowed)
			)
			(placement
				(enabled no)
				(sheetname "")
			)
			(fill
				(thermal_gap 0.5)
				(thermal_bridge_width 0.5)
				(island_removal_mode 0)
			)
			(polygon
				(pts
					(xy 432.2572 -23.1648) (xy 431.7492 -23.1648) (xy 431.7492 -22.7838) (xy 432.2572 -22.7838)
				)
			)
		)
		(zone
			(layer "B.Cu")
			(hatch none 0.5)
			(connect_pads
				(clearance 0)
			)
			(min_thickness 0.25)
			(keepout
				(tracks not_allowed)
				(vias allowed)
				(pads allowed)
				(copperpour not_allowed)
				(footprints allowed)
			)
			(placement
				(enabled no)
				(sheetname "")
			)
			(fill
				(thermal_gap 0.5)
				(thermal_bridge_width 0.5)
				(island_removal_mode 0)
			)
			(polygon
				(pts
					(xy 432.2572 -22.7838) (xy 431.7492 -22.7838) (xy 431.7492 -23.1648) (xy 432.2572 -23.1648)
				)
			)
		)
	)
	(footprint ""
		(layer "B.Cu")
		(at 363.87024 -138.41857 90)
		(property "Reference" "R3L11"
			(at 0 0 90)
			(layer "B.SilkS")
			(hide yes)
			(effects
				(font
					(size 1.27 1.27)
				)
				(justify mirror)
			)
		)
		(property "Value" ""
			(at 0 0 90)
			(layer "B.Fab")
			(effects
				(font
					(size 1.27 1.27)
				)
				(justify mirror)
			)
		)
		(duplicate_pad_numbers_are_jumpers no)
		(fp_rect
			(start -0.2794 -0.1016)
			(end 0.2794 0.9906)
			(stroke
				(width 0)
				(type default)
			)
			(fill no)
			(layer "B.CrtYd")
		)
		(fp_line
			(start 0.2794 -0.1016)
			(end 0.2794 0.9906)
			(stroke
				(width 0.1)
				(type default)
			)
			(layer "B.Fab")
		)
		(fp_line
			(start -0.2794 -0.1016)
			(end 0.2794 -0.1016)
			(stroke
				(width 0.1)
				(type default)
			)
			(layer "B.Fab")
		)
		(fp_line
			(start 0.2794 0.9906)
			(end -0.2794 0.9906)
			(stroke
				(width 0.1)
				(type default)
			)
			(layer "B.Fab")
		)
		(fp_line
			(start -0.2794 0.9906)
			(end -0.2794 -0.1016)
			(stroke
				(width 0.1)
				(type default)
			)
			(layer "B.Fab")
		)
		(pad "1" smd rect
			(at 0 0 270)
			(size 0.508 0.508)
			(layers "B.Cu" "B.Mask" "B.Paste")
			(net "PVCCIO_CPU0")
		)
		(pad "2" smd rect
			(at 0 0.889 270)
			(size 0.508 0.508)
			(layers "B.Cu" "B.Mask" "B.Paste")
			(net "SVID_DIO1_CPU0_R")
		)
		(zone
			(layer "B.Cu")
			(hatch none 0.5)
			(connect_pads
				(clearance 0)
			)
			(min_thickness 0.25)
			(keepout
				(tracks not_allowed)
				(vias allowed)
				(pads allowed)
				(copperpour not_allowed)
				(footprints allowed)
			)
			(placement
				(enabled no)
				(sheetname "")
			)
			(fill
				(thermal_gap 0.5)
				(thermal_bridge_width 0.5)
				(island_removal_mode 0)
			)
			(polygon
				(pts
					(xy 364.12424 -138.16457) (xy 364.50524 -138.16457) (xy 364.50524 -138.67257) (xy 364.12424 -138.67257)
				)
			)
		)
		(zone
			(layer "B.Cu")
			(hatch none 0.5)
			(connect_pads
				(clearance 0)
			)
			(min_thickness 0.25)
			(keepout
				(tracks allowed)
				(vias not_allowed)
				(pads allowed)
				(copperpour not_allowed)
				(footprints allowed)
			)
			(placement
				(enabled no)
				(sheetname "")
			)
			(fill
				(thermal_gap 0.5)
				(thermal_bridge_width 0.5)
				(island_removal_mode 0)
			)
			(polygon
				(pts
					(xy 364.12424 -138.16457) (xy 364.50524 -138.16457) (xy 364.50524 -138.67257) (xy 364.12424 -138.67257)
				)
			)
		)
	)
	(footprint ""
		(layer "B.Cu")
		(at 479.95205 4.714748 180)
		(property "Reference" "C9F22"
			(at 0 0 0)
			(layer "B.SilkS")
			(hide yes)
			(effects
				(font
					(size 1.27 1.27)
				)
				(justify mirror)
			)
		)
		(property "Value" ""
			(at 0 0 0)
			(layer "B.Fab")
			(effects
				(font
					(size 1.27 1.27)
				)
				(justify mirror)
			)
		)
		(duplicate_pad_numbers_are_jumpers no)
		(fp_poly
			(pts
				(xy -0.3048 -0.1016) (xy -0.3048 0.9906) (xy 0.3048 0.9906) (xy 0.3048 -0.1016)
			)
			(stroke
				(width 0)
				(type default)
			)
			(fill no)
			(layer "B.CrtYd")
		)
		(fp_line
			(start 0.3048 0.9906)
			(end -0.3048 0.9906)
			(stroke
				(width 0.1)
				(type default)
			)
			(layer "B.Fab")
		)
		(fp_line
			(start 0.3048 -0.1016)
			(end 0.3048 0.9906)
			(stroke
				(width 0.1)
				(type default)
			)
			(layer "B.Fab")
		)
		(fp_line
			(start -0.3048 0.9906)
			(end -0.3048 -0.1016)
			(stroke
				(width 0.1)
				(type default)
			)
			(layer "B.Fab")
		)
		(fp_line
			(start -0.3048 -0.1016)
			(end 0.3048 -0.1016)
			(stroke
				(width 0.1)
				(type default)
			)
			(layer "B.Fab")
		)
		(pad "1" smd rect
			(at 0 0)
			(size 0.508 0.508)
			(layers "B.Cu" "B.Mask" "B.Paste")
			(net "LED_LAN_1_N")
		)
		(pad "2" smd rect
			(at 0 0.889)
			(size 0.508 0.508)
			(layers "B.Cu" "B.Mask" "B.Paste")
			(net "GND")
		)
		(zone
			(layer "B.Cu")
			(hatch none 0.5)
			(connect_pads
				(clearance 0)
			)
			(min_thickness 0.25)
			(keepout
				(tracks not_allowed)
				(vias allowed)
				(pads allowed)
				(copperpour not_allowed)
				(footprints allowed)
			)
			(placement
				(enabled no)
				(sheetname "")
			)
			(fill
				(thermal_gap 0.5)
				(thermal_bridge_width 0.5)
				(island_removal_mode 0)
			)
			(polygon
				(pts
					(xy 479.69805 4.079748) (xy 480.20605 4.079748) (xy 480.20605 4.460748) (xy 479.69805 4.460748)
				)
			)
		)
		(zone
			(layer "B.Cu")
			(hatch none 0.5)
			(connect_pads
				(clearance 0)
			)
			(min_thickness 0.25)
			(keepout
				(tracks allowed)
				(vias not_allowed)
				(pads allowed)
				(copperpour not_allowed)
				(footprints allowed)
			)
			(placement
				(enabled no)
				(sheetname "")
			)
			(fill
				(thermal_gap 0.5)
				(thermal_bridge_width 0.5)
				(island_removal_mode 0)
			)
			(polygon
				(pts
					(xy 479.69805 4.460748) (xy 480.20605 4.460748) (xy 480.20605 4.079748) (xy 479.69805 4.079748)
				)
			)
		)
	)
	(footprint ""
		(layer "B.Cu")
		(at 347.469206 1.043178 -90)
		(property "Reference" "C3U6"
			(at 0 0 90)
			(layer "B.SilkS")
			(hide yes)
			(effects
				(font
					(size 1.27 1.27)
				)
				(justify mirror)
			)
		)
		(property "Value" ""
			(at 0 0 90)
			(layer "B.Fab")
			(effects
				(font
					(size 1.27 1.27)
				)
				(justify mirror)
			)
		)
		(duplicate_pad_numbers_are_jumpers no)
		(fp_rect
			(start 0.7239 1.9939)
			(end -0.7239 -0.2159)
			(stroke
				(width 0)
				(type default)
			)
			(fill no)
			(layer "B.CrtYd")
		)
		(fp_line
			(start -0.7239 1.9939)
			(end -0.7239 -0.2159)
			(stroke
				(width 0.1)
				(type default)
			)
			(layer "B.Fab")
		)
		(fp_line
			(start 0.7239 1.9939)
			(end -0.7239 1.9939)
			(stroke
				(width 0.1)
				(type default)
			)
			(layer "B.Fab")
		)
		(fp_line
			(start -0.7239 -0.2159)
			(end 0.7239 -0.2159)
			(stroke
				(width 0.1)
				(type default)
			)
			(layer "B.Fab")
		)
		(fp_line
			(start 0.7239 -0.2159)
			(end 0.7239 1.9939)
			(stroke
				(width 0.1)
				(type default)
			)
			(layer "B.Fab")
		)
		(pad "1" smd rect
			(at 0 0 90)
			(size 1.27 1.016)
			(layers "B.Cu" "B.Mask" "B.Paste")
			(net "VR_FET_SW_P12V_STBY_PVDDQ_ABC")
		)
		(pad "2" smd rect
			(at 0 1.778 90)
			(size 1.27 1.016)
			(layers "B.Cu" "B.Mask" "B.Paste")
			(net "GND")
		)
		(zone
			(layer "B.Cu")
			(hatch none 0.5)
			(connect_pads
				(clearance 0)
			)
			(min_thickness 0.25)
			(keepout
				(tracks not_allowed)
				(vias allowed)
				(pads allowed)
				(copperpour not_allowed)
				(footprints allowed)
			)
			(placement
				(enabled no)
				(sheetname "")
			)
			(fill
				(thermal_gap 0.5)
				(thermal_bridge_width 0.5)
				(island_removal_mode 0)
			)
			(polygon
				(pts
					(xy 346.199206 1.678178) (xy 346.961206 1.678178) (xy 346.961206 0.408178) (xy 346.199206 0.408178)
				)
			)
		)
	)
	(footprint ""
		(layer "B.Cu")
		(at 479.9838 -42.5958 90)
		(property "Reference" "C1R24"
			(at 0 0 90)
			(layer "B.SilkS")
			(hide yes)
			(effects
				(font
					(size 1.27 1.27)
				)
				(justify mirror)
			)
		)
		(property "Value" ""
			(at 0 0 90)
			(layer "B.Fab")
			(effects
				(font
					(size 1.27 1.27)
				)
				(justify mirror)
			)
		)
		(duplicate_pad_numbers_are_jumpers no)
		(fp_poly
			(pts
				(xy -0.3048 -0.1016) (xy -0.3048 0.9906) (xy 0.3048 0.9906) (xy 0.3048 -0.1016)
			)
			(stroke
				(width 0)
				(type default)
			)
			(fill no)
			(layer "B.CrtYd")
		)
		(fp_line
			(start 0.3048 -0.1016)
			(end 0.3048 0.9906)
			(stroke
				(width 0.1)
				(type default)
			)
			(layer "B.Fab")
		)
		(fp_line
			(start -0.3048 -0.1016)
			(end 0.3048 -0.1016)
			(stroke
				(width 0.1)
				(type default)
			)
			(layer "B.Fab")
		)
		(fp_line
			(start 0.3048 0.9906)
			(end -0.3048 0.9906)
			(stroke
				(width 0.1)
				(type default)
			)
			(layer "B.Fab")
		)
		(fp_line
			(start -0.3048 0.9906)
			(end -0.3048 -0.1016)
			(stroke
				(width 0.1)
				(type default)
			)
			(layer "B.Fab")
		)
		(pad "1" smd rect
			(at 0 0 270)
			(size 0.508 0.508)
			(layers "B.Cu" "B.Mask" "B.Paste")
			(net "P0V9_LAN")
		)
		(pad "2" smd rect
			(at 0 0.889 270)
			(size 0.508 0.508)
			(layers "B.Cu" "B.Mask" "B.Paste")
			(net "GND")
		)
		(zone
			(layer "B.Cu")
			(hatch none 0.5)
			(connect_pads
				(clearance 0)
			)
			(min_thickness 0.25)
			(keepout
				(tracks allowed)
				(vias not_allowed)
				(pads allowed)
				(copperpour not_allowed)
				(footprints allowed)
			)
			(placement
				(enabled no)
				(sheetname "")
			)
			(fill
				(thermal_gap 0.5)
				(thermal_bridge_width 0.5)
				(island_removal_mode 0)
			)
			(polygon
				(pts
					(xy 480.2378 -42.8498) (xy 480.2378 -42.3418) (xy 480.6188 -42.3418) (xy 480.6188 -42.8498)
				)
			)
		)
		(zone
			(layer "B.Cu")
			(hatch none 0.5)
			(connect_pads
				(clearance 0)
			)
			(min_thickness 0.25)
			(keepout
				(tracks not_allowed)
				(vias allowed)
				(pads allowed)
				(copperpour not_allowed)
				(footprints allowed)
			)
			(placement
				(enabled no)
				(sheetname "")
			)
			(fill
				(thermal_gap 0.5)
				(thermal_bridge_width 0.5)
				(island_removal_mode 0)
			)
			(polygon
				(pts
					(xy 480.6188 -42.8498) (xy 480.6188 -42.3418) (xy 480.2378 -42.3418) (xy 480.2378 -42.8498)
				)
			)
		)
	)
	(footprint ""
		(layer "B.Cu")
		(at 466.5472 -123.444 -90)
		(property "Reference" "R1W10"
			(at -1.47828 0.78994 0)
			(unlocked yes)
			(layer "B.SilkS")
			(effects
				(font
					(size 0.4064 0.254)
					(thickness 0.1524)
				)
				(justify mirror)
			)
		)
		(property "Value" ""
			(at 0 0 90)
			(layer "B.Fab")
			(effects
				(font
					(size 1.27 1.27)
				)
				(justify mirror)
			)
		)
		(duplicate_pad_numbers_are_jumpers no)
		(fp_poly
			(pts
				(xy 0.7239 -0.2159) (xy -0.7239 -0.2159) (xy -0.7239 1.9939) (xy 0.7239 1.9939)
			)
			(stroke
				(width 0)
				(type default)
			)
			(fill no)
			(layer "B.CrtYd")
		)
		(fp_line
			(start -0.7239 1.9939)
			(end -0.7239 -0.2159)
			(stroke
				(width 0.1)
				(type default)
			)
			(layer "B.Fab")
		)
		(fp_line
			(start 0.7239 1.9939)
			(end -0.7239 1.9939)
			(stroke
				(width 0.1)
				(type default)
			)
			(layer "B.Fab")
		)
		(fp_line
			(start -0.7239 -0.2159)
			(end 0.7239 -0.2159)
			(stroke
				(width 0.1)
				(type default)
			)
			(layer "B.Fab")
		)
		(fp_line
			(start 0.7239 -0.2159)
			(end 0.7239 1.9939)
			(stroke
				(width 0.1)
				(type default)
			)
			(layer "B.Fab")
		)
		(pad "1" smd rect
			(at 0 0 90)
			(size 1.27 1.016)
			(layers "B.Cu" "B.Mask" "B.Paste")
			(net "P5V_STBY")
		)
		(pad "2" smd rect
			(at 0 1.778 90)
			(size 1.27 1.016)
			(layers "B.Cu" "B.Mask" "B.Paste")
			(net "P5V_TPS2061")
		)
		(zone
			(layer "B.Cu")
			(hatch none 0.5)
			(connect_pads
				(clearance 0)
			)
			(min_thickness 0.25)
			(keepout
				(tracks not_allowed)
				(vias allowed)
				(pads allowed)
				(copperpour not_allowed)
				(footprints allowed)
			)
			(placement
				(enabled no)
				(sheetname "")
			)
			(fill
				(thermal_gap 0.5)
				(thermal_bridge_width 0.5)
				(island_removal_mode 0)
			)
			(polygon
				(pts
					(xy 466.0392 -124.079) (xy 465.2772 -124.079) (xy 465.2772 -123.9901) (xy 465.2772 -122.809) (xy 466.0392 -122.809)
				)
			)
		)
	)
	(footprint ""
		(layer "B.Cu")
		(at 489.417614 -47.930054 90)
		(property "Reference" "R25W134"
			(at 0.8382 -0.67818 90)
			(unlocked yes)
			(layer "B.SilkS")
			(effects
				(font
					(size 0.4064 0.254)
					(thickness 0.1524)
				)
				(justify left mirror)
			)
		)
		(property "Value" ""
			(at 0 0 90)
			(layer "B.Fab")
			(effects
				(font
					(size 1.27 1.27)
				)
				(justify mirror)
			)
		)
		(duplicate_pad_numbers_are_jumpers no)
		(fp_poly
			(pts
				(xy 0.2794 -0.1016) (xy -0.2794 -0.1016) (xy -0.2794 0.9906) (xy 0.2794 0.9906)
			)
			(stroke
				(width 0)
				(type default)
			)
			(fill no)
			(layer "B.CrtYd")
		)
		(fp_line
			(start 0.2794 -0.1016)
			(end 0.2794 0.9906)
			(stroke
				(width 0.1)
				(type default)
			)
			(layer "B.Fab")
		)
		(fp_line
			(start -0.2794 -0.1016)
			(end 0.2794 -0.1016)
			(stroke
				(width 0.1)
				(type default)
			)
			(layer "B.Fab")
		)
		(fp_line
			(start 0.2794 0.9906)
			(end -0.2794 0.9906)
			(stroke
				(width 0.1)
				(type default)
			)
			(layer "B.Fab")
		)
		(fp_line
			(start -0.2794 0.9906)
			(end -0.2794 -0.1016)
			(stroke
				(width 0.1)
				(type default)
			)
			(layer "B.Fab")
		)
		(pad "1" smd rect
			(at 0 0 270)
			(size 0.508 0.508)
			(layers "B.Cu" "B.Mask" "B.Paste")
			(net "P3V3")
		)
		(pad "2" smd rect
			(at 0 0.889 270)
			(size 0.508 0.508)
			(layers "B.Cu" "B.Mask" "B.Paste")
			(net "Q25W2_GATE")
		)
		(zone
			(layer "B.Cu")
			(hatch none 0.5)
			(connect_pads
				(clearance 0)
			)
			(min_thickness 0.25)
			(keepout
				(tracks allowed)
				(vias not_allowed)
				(pads allowed)
				(copperpour not_allowed)
				(footprints allowed)
			)
			(placement
				(enabled no)
				(sheetname "")
			)
			(fill
				(thermal_gap 0.5)
				(thermal_bridge_width 0.5)
				(island_removal_mode 0)
			)
			(polygon
				(pts
					(xy 489.671614 -48.184054) (xy 489.671614 -47.676054) (xy 490.052614 -47.676054) (xy 490.052614 -48.184054)
				)
			)
		)
		(zone
			(layer "B.Cu")
			(hatch none 0.5)
			(connect_pads
				(clearance 0)
			)
			(min_thickness 0.25)
			(keepout
				(tracks not_allowed)
				(vias allowed)
				(pads allowed)
				(copperpour not_allowed)
				(footprints allowed)
			)
			(placement
				(enabled no)
				(sheetname "")
			)
			(fill
				(thermal_gap 0.5)
				(thermal_bridge_width 0.5)
				(island_removal_mode 0)
			)
			(polygon
				(pts
					(xy 490.052614 -48.184054) (xy 490.052614 -47.676054) (xy 489.671614 -47.676054) (xy 489.671614 -48.184054)
				)
			)
		)
	)
	(footprint ""
		(layer "B.Cu")
		(at 281.3812 -74.803 90)
		(property "Reference" "R4P7"
			(at 0 0 90)
			(layer "B.SilkS")
			(hide yes)
			(effects
				(font
					(size 1.27 1.27)
				)
				(justify mirror)
			)
		)
		(property "Value" ""
			(at 0 0 90)
			(layer "B.Fab")
			(effects
				(font
					(size 1.27 1.27)
				)
				(justify mirror)
			)
		)
		(duplicate_pad_numbers_are_jumpers no)
		(fp_rect
			(start -0.2794 -0.1016)
			(end 0.2794 0.9906)
			(stroke
				(width 0)
				(type default)
			)
			(fill no)
			(layer "B.CrtYd")
		)
		(fp_line
			(start 0.2794 -0.1016)
			(end 0.2794 0.9906)
			(stroke
				(width 0.1)
				(type default)
			)
			(layer "B.Fab")
		)
		(fp_line
			(start -0.2794 -0.1016)
			(end 0.2794 -0.1016)
			(stroke
				(width 0.1)
				(type default)
			)
			(layer "B.Fab")
		)
		(fp_line
			(start 0.2794 0.9906)
			(end -0.2794 0.9906)
			(stroke
				(width 0.1)
				(type default)
			)
			(layer "B.Fab")
		)
		(fp_line
			(start -0.2794 0.9906)
			(end -0.2794 -0.1016)
			(stroke
				(width 0.1)
				(type default)
			)
			(layer "B.Fab")
		)
		(pad "1" smd rect
			(at 0 0 270)
			(size 0.508 0.508)
			(layers "B.Cu" "B.Mask" "B.Paste")
			(net "GND")
		)
		(pad "2" smd rect
			(at 0 0.889 270)
			(size 0.508 0.508)
			(layers "B.Cu" "B.Mask" "B.Paste")
			(net "PD_CPU0_KSFC_DIS")
		)
		(zone
			(layer "B.Cu")
			(hatch none 0.5)
			(connect_pads
				(clearance 0)
			)
			(min_thickness 0.25)
			(keepout
				(tracks allowed)
				(vias not_allowed)
				(pads allowed)
				(copperpour not_allowed)
				(footprints allowed)
			)
			(placement
				(enabled no)
				(sheetname "")
			)
			(fill
				(thermal_gap 0.5)
				(thermal_bridge_width 0.5)
				(island_removal_mode 0)
			)
			(polygon
				(pts
					(xy 281.6352 -74.549) (xy 282.0162 -74.549) (xy 282.0162 -75.057) (xy 281.6352 -75.057)
				)
			)
		)
		(zone
			(layer "B.Cu")
			(hatch none 0.5)
			(connect_pads
				(clearance 0)
			)
			(min_thickness 0.25)
			(keepout
				(tracks not_allowed)
				(vias allowed)
				(pads allowed)
				(copperpour not_allowed)
				(footprints allowed)
			)
			(placement
				(enabled no)
				(sheetname "")
			)
			(fill
				(thermal_gap 0.5)
				(thermal_bridge_width 0.5)
				(island_removal_mode 0)
			)
			(polygon
				(pts
					(xy 281.6352 -74.549) (xy 282.0162 -74.549) (xy 282.0162 -75.057) (xy 281.6352 -75.057)
				)
			)
		)
	)
)
